# T6G (Grand Teton) — schematic netlist excerpt (pin names and nets, part order shuffled) for the footprints in the layout excerpt that follows; sources: Cadence DE-HDL packaged netlist, KiCad conversion of 04192023_DAF0TMB3IC0_F0TG_MB_C_brd_V02_OCP.brd

R1328  Q_RES  1K 1% EMPTY  pkg 0402LF  page 357 : A = P3V3_AUX ; B = OCP_V3_2_P3V3_P12V_ADC_R_ALERT
R3658  Q_RES  10K 1% EMPTY  pkg 0402LF  page 234 : A = P3V3_AUX ; B = USB_HUB_OVCUR3
R1398  Q_RES  10K 1% CHIP  pkg 0201LF  page 287 : A = RXDET_BYP_RT_CPU0_P1 ; B = GND

(kicad_pcb
	(version 20260206)
	(generator "pcbnew")
	(generator_version "10.0")
	(general
		(thickness 1.6)
		(legacy_teardrops no)
	)
	(paper "A4")
	(title_block
		(title "04192023_DAF0TMB3IC0_F0TG_MB_C_brd_V02_OCP.brd")
		(comment 1 "Grand Teton / footprints 3724-3726 of 8354")
	)
	(layers
		(0 "F.Cu" signal "TOP")
		(4 "In1.Cu" signal "GND")
		(6 "In2.Cu" signal "IN1")
		(8 "In3.Cu" signal "GND1")
		(10 "In4.Cu" signal "IN2")
		(12 "In5.Cu" signal "GND2")
		(14 "In6.Cu" signal "IN3")
		(16 "In7.Cu" signal "GND3")
		(18 "In8.Cu" signal "VCC")
		(20 "In9.Cu" signal "VCC1")
		(22 "In10.Cu" signal "GND4")
		(24 "In11.Cu" signal "IN4")
		(26 "In12.Cu" signal "GND5")
		(28 "In13.Cu" signal "IN5")
		(30 "In14.Cu" signal "GND6")
		(32 "In15.Cu" signal "IN6")
		(34 "In16.Cu" signal "GND7")
		(2 "B.Cu" signal "BOTTOM")
		(9 "F.Adhes" user "F.Adhesive")
		(11 "B.Adhes" user "B.Adhesive")
		(13 "F.Paste" user "Package Geometry/Pastemask Top")
		(15 "B.Paste" user "Package Geometry/Pastemask Bottom")
		(5 "F.SilkS" user "Ref Des/Silkscreen Top")
		(7 "B.SilkS" user "Ref Des/Silkscreen Bottom")
		(1 "F.Mask" user "Board Geometry/Soldermask Top")
		(3 "B.Mask" user "Board Geometry/Soldermask Bottom")
		(17 "Dwgs.User" user "User.Drawings")
		(19 "Cmts.User" user "User.Comments")
		(21 "Eco1.User" user "User.Eco1")
		(23 "Eco2.User" user "User.Eco2")
		(25 "Edge.Cuts" user "Board Geometry/Outline")
		(27 "Margin" user)
		(31 "F.CrtYd" user "Package Geometry/Place Bound Top")
		(29 "B.CrtYd" user "Package Geometry/Place Bound Bottom")
		(35 "F.Fab" user "Ref Des/Assembly Top")
		(33 "B.Fab" user "Ref Des/Assembly Bottom")
	)
	(footprint ""
		(layer "F.Cu")
		(at 16.110966 -92.687648 90)
		(property "Reference" "R3658"
			(at 0 0 90)
			(layer "F.SilkS")
			(hide yes)
			(effects
				(font
					(size 1.27 1.27)
				)
			)
		)
		(property "Value" ""
			(at 0 0 90)
			(layer "F.Fab")
			(effects
				(font
					(size 1.27 1.27)
				)
			)
		)
		(duplicate_pad_numbers_are_jumpers no)
		(fp_line
			(start 0.7874 -0.4064)
			(end 0.7874 0.4064)
			(stroke
				(width 0.1524)
				(type default)
			)
			(layer "F.SilkS")
		)
		(fp_line
			(start -0.7874 -0.4064)
			(end 0.7874 -0.4064)
			(stroke
				(width 0.1524)
				(type default)
			)
			(layer "F.SilkS")
		)
		(fp_line
			(start 0.7874 0.4064)
			(end -0.7874 0.4064)
			(stroke
				(width 0.1524)
				(type default)
			)
			(layer "F.SilkS")
		)
		(fp_line
			(start -0.7874 0.4064)
			(end -0.7874 -0.4064)
			(stroke
				(width 0.1524)
				(type default)
			)
			(layer "F.SilkS")
		)
		(fp_line
			(start -0.12065 -0.305054)
			(end -0.12065 -0.2794)
			(stroke
				(width 0.1)
				(type default)
			)
			(layer "F.Fab")
		)
		(fp_line
			(start -0.67945 -0.305054)
			(end -0.12065 -0.305054)
			(stroke
				(width 0.1)
				(type default)
			)
			(layer "F.Fab")
		)
		(fp_line
			(start 0.67945 -0.3048)
			(end 0.67945 0.3048)
			(stroke
				(width 0.1)
				(type default)
			)
			(layer "F.Fab")
		)
		(fp_line
			(start 0.12065 -0.3048)
			(end 0.67945 -0.3048)
			(stroke
				(width 0.1)
				(type default)
			)
			(layer "F.Fab")
		)
		(fp_line
			(start 0.12065 -0.2794)
			(end 0.12065 -0.3048)
			(stroke
				(width 0.1)
				(type default)
			)
			(layer "F.Fab")
		)
		(fp_line
			(start -0.12065 -0.2794)
			(end 0.12065 -0.2794)
			(stroke
				(width 0.1)
				(type default)
			)
			(layer "F.Fab")
		)
		(fp_line
			(start 0.120396 0.2794)
			(end -0.12065 0.2794)
			(stroke
				(width 0.1)
				(type default)
			)
			(layer "F.Fab")
		)
		(fp_line
			(start -0.12065 0.2794)
			(end -0.12065 0.3048)
			(stroke
				(width 0.1)
				(type default)
			)
			(layer "F.Fab")
		)
		(fp_line
			(start 0.67945 0.3048)
			(end 0.120396 0.3048)
			(stroke
				(width 0.1)
				(type default)
			)
			(layer "F.Fab")
		)
		(fp_line
			(start 0.120396 0.3048)
			(end 0.120396 0.2794)
			(stroke
				(width 0.1)
				(type default)
			)
			(layer "F.Fab")
		)
		(fp_line
			(start -0.12065 0.3048)
			(end -0.67945 0.3048)
			(stroke
				(width 0.1)
				(type default)
			)
			(layer "F.Fab")
		)
		(fp_line
			(start -0.67945 0.3048)
			(end -0.67945 -0.305054)
			(stroke
				(width 0.1)
				(type default)
			)
			(layer "F.Fab")
		)
		(pad "1" smd circle
			(at -0.40005 0 90)
			(size 0 0)
			(layers "F.Cu" "F.Mask" "F.Paste")
			(net "P3V3_AUX")
		)
		(pad "2" smd circle
			(at 0.40005 0 90)
			(size 0 0)
			(layers "F.Cu" "F.Mask" "F.Paste")
			(net "USB_HUB_OVCUR3")
		)
	)
	(footprint ""
		(layer "F.Cu")
		(at 360.762042 -397.87576)
		(property "Reference" "R1398"
			(at 0 0 0)
			(layer "F.SilkS")
			(hide yes)
			(effects
				(font
					(size 1.27 1.27)
				)
			)
		)
		(property "Value" ""
			(at 0 0 0)
			(layer "F.Fab")
			(effects
				(font
					(size 1.27 1.27)
				)
			)
		)
		(duplicate_pad_numbers_are_jumpers no)
		(fp_line
			(start -0.32512 -0.175006)
			(end 0.32512 -0.175006)
			(stroke
				(width 0.1)
				(type default)
			)
			(layer "F.Fab")
		)
		(fp_line
			(start -0.32512 0.175006)
			(end -0.32512 -0.175006)
			(stroke
				(width 0.1)
				(type default)
			)
			(layer "F.Fab")
		)
		(fp_line
			(start 0.32512 -0.175006)
			(end 0.32512 0.175006)
			(stroke
				(width 0.1)
				(type default)
			)
			(layer "F.Fab")
		)
		(fp_line
			(start 0.32512 0.175006)
			(end -0.32512 0.175006)
			(stroke
				(width 0.1)
				(type default)
			)
			(layer "F.Fab")
		)
		(pad "1" smd rect
			(at -0.2667 0)
			(size 0.3048 0.381)
			(layers "F.Cu" "F.Mask" "F.Paste")
			(net "RXDET_BYP_RT_CPU0_P1")
		)
		(pad "2" smd rect
			(at 0.2667 0 180)
			(size 0.3048 0.381)
			(layers "F.Cu" "F.Mask" "F.Paste")
			(net "GND")
		)
	)
	(footprint ""
		(layer "F.Cu")
		(at 19.240754 -36.878514 180)
		(property "Reference" "R1328"
			(at 0 0 180)
			(layer "F.SilkS")
			(hide yes)
			(effects
				(font
					(size 1.27 1.27)
				)
			)
		)
		(property "Value" ""
			(at 0 0 180)
			(layer "F.Fab")
			(effects
				(font
					(size 1.27 1.27)
				)
			)
		)
		(duplicate_pad_numbers_are_jumpers no)
		(fp_line
			(start 0.7874 0.4064)
			(end -0.7874 0.4064)
			(stroke
				(width 0.1524)
				(type default)
			)
			(layer "F.SilkS")
		)
		(fp_line
			(start 0.7874 -0.4064)
			(end 0.7874 0.4064)
			(stroke
				(width 0.1524)
				(type default)
			)
			(layer "F.SilkS")
		)
		(fp_line
			(start -0.7874 0.4064)
			(end -0.7874 -0.4064)
			(stroke
				(width 0.1524)
				(type default)
			)
			(layer "F.SilkS")
		)
		(fp_line
			(start -0.7874 -0.4064)
			(end 0.7874 -0.4064)
			(stroke
				(width 0.1524)
				(type default)
			)
			(layer "F.SilkS")
		)
		(fp_line
			(start 0.67945 0.3048)
			(end 0.120396 0.3048)
			(stroke
				(width 0.1)
				(type default)
			)
			(layer "F.Fab")
		)
		(fp_line
			(start 0.67945 -0.3048)
			(end 0.67945 0.3048)
			(stroke
				(width 0.1)
				(type default)
			)
			(layer "F.Fab")
		)
		(fp_line
			(start 0.12065 -0.2794)
			(end 0.12065 -0.3048)
			(stroke
				(width 0.1)
				(type default)
			)
			(layer "F.Fab")
		)
		(fp_line
			(start 0.12065 -0.3048)
			(end 0.67945 -0.3048)
			(stroke
				(width 0.1)
				(type default)
			)
			(layer "F.Fab")
		)
		(fp_line
			(start 0.120396 0.3048)
			(end 0.120396 0.2794)
			(stroke
				(width 0.1)
				(type default)
			)
			(layer "F.Fab")
		)
		(fp_line
			(start 0.120396 0.2794)
			(end -0.12065 0.2794)
			(stroke
				(width 0.1)
				(type default)
			)
			(layer "F.Fab")
		)
		(fp_line
			(start -0.12065 0.3048)
			(end -0.67945 0.3048)
			(stroke
				(width 0.1)
				(type default)
			)
			(layer "F.Fab")
		)
		(fp_line
			(start -0.12065 0.2794)
			(end -0.12065 0.3048)
			(stroke
				(width 0.1)
				(type default)
			)
			(layer "F.Fab")
		)
		(fp_line
			(start -0.12065 -0.2794)
			(end 0.12065 -0.2794)
			(stroke
				(width 0.1)
				(type default)
			)
			(layer "F.Fab")
		)
		(fp_line
			(start -0.12065 -0.305054)
			(end -0.12065 -0.2794)
			(stroke
				(width 0.1)
				(type default)
			)
			(layer "F.Fab")
		)
		(fp_line
			(start -0.67945 0.3048)
			(end -0.67945 -0.305054)
			(stroke
				(width 0.1)
				(type default)
			)
			(layer "F.Fab")
		)
		(fp_line
			(start -0.67945 -0.305054)
			(end -0.12065 -0.305054)
			(stroke
				(width 0.1)
				(type default)
			)
			(layer "F.Fab")
		)
		(pad "1" smd circle
			(at -0.40005 0 180)
			(size 0 0)
			(layers "F.Cu" "F.Mask" "F.Paste")
			(net "P3V3_AUX")
		)
		(pad "2" smd circle
			(at 0.40005 0 180)
			(size 0 0)
			(layers "F.Cu" "F.Mask" "F.Paste")
			(net "OCP_V3_2_P3V3_P12V_ADC_R_ALERT")
		)
	)
)
